(kicad_pcb
	(version 20260206)
	(generator "pcbnew")
	(generator_version "10.0")
	(general
		(thickness 1.6)
		(legacy_teardrops no)
	)
	(paper "A4")
	(title_block
		(title "Bryce Canyon_R.DPB_16317-1_OCP.brd")
		(comment 1 "Bryce Canyon / footprints 2023-2028 of 2099")
	)
	(layers
		(0 "F.Cu" signal "TOP")
		(4 "In1.Cu" signal "L2GND")
		(6 "In2.Cu" signal "L3")
		(8 "In3.Cu" signal "L4VCC")
		(10 "In4.Cu" signal "L5VCC")
		(12 "In5.Cu" signal "L6")
		(14 "In6.Cu" signal "L7GND")
		(2 "B.Cu" signal "BOTTOM")
		(9 "F.Adhes" user "F.Adhesive")
		(11 "B.Adhes" user "B.Adhesive")
		(13 "F.Paste" user "Package Geometry/Pastemask Top")
		(15 "B.Paste" user "Package Geometry/Pastemask Bottom")
		(5 "F.SilkS" user "Ref Des/Silkscreen Top")
		(7 "B.SilkS" user "Ref Des/Silkscreen Bottom")
		(1 "F.Mask" user "Board Geometry/Soldermask Top")
		(3 "B.Mask" user "Board Geometry/Soldermask Bottom")
		(17 "Dwgs.User" user "User.Drawings")
		(19 "Cmts.User" user "User.Comments")
		(21 "Eco1.User" user "User.Eco1")
		(23 "Eco2.User" user "User.Eco2")
		(25 "Edge.Cuts" user "Board Geometry/Outline")
		(27 "Margin" user)
		(31 "F.CrtYd" user "Package Geometry/Place Bound Top")
		(29 "B.CrtYd" user "Package Geometry/Place Bound Bottom")
		(35 "F.Fab" user "Ref Des/Assembly Top")
		(33 "B.Fab" user "Ref Des/Assembly Bottom")
	)
	(footprint ""
		(layer "B.Cu")
		(at 476.6564 -220.11259)
		(property "Reference" "TC10"
			(at 0 0 0)
			(layer "B.SilkS")
			(hide yes)
			(effects
				(font
					(size 1.27 1.27)
				)
				(justify mirror)
			)
		)
		(property "Value" "ST220U10VDM-LGP"
			(at 0 -9.6012 0)
			(unlocked yes)
			(layer "B.Fab")
			(hide yes)
			(effects
				(font
					(size 1.016 1.016)
					(thickness 0.1524)
				)
				(justify mirror)
			)
		)
		(property "Device Type" "CT7343H119"
			(at 0 -11.1252 0)
			(unlocked yes)
			(layer "B.Fab")
			(hide yes)
			(effects
				(font
					(size 1.016 1.016)
					(thickness 0.1524)
				)
				(justify mirror)
			)
		)
		(duplicate_pad_numbers_are_jumpers no)
		(fp_line
			(start -2.286 -4.8768)
			(end 2.286 -4.8768)
			(stroke
				(width 0.1524)
				(type default)
			)
			(layer "B.SilkS")
		)
		(fp_line
			(start -2.286 -2.032)
			(end -2.286 -4.8768)
			(stroke
				(width 0.1524)
				(type default)
			)
			(layer "B.SilkS")
		)
		(fp_line
			(start -2.286 2.032)
			(end -2.286 4.8768)
			(stroke
				(width 0.1524)
				(type default)
			)
			(layer "B.SilkS")
		)
		(fp_line
			(start -2.286 4.8768)
			(end 2.286 4.8768)
			(stroke
				(width 0.1524)
				(type default)
			)
			(layer "B.SilkS")
		)
		(fp_line
			(start -2.1082 -4.699)
			(end 2.1082 -4.699)
			(stroke
				(width 0.508)
				(type default)
			)
			(layer "B.SilkS")
		)
		(fp_line
			(start 2.286 -4.8768)
			(end 2.286 -2.032)
			(stroke
				(width 0.1524)
				(type default)
			)
			(layer "B.SilkS")
		)
		(fp_line
			(start 2.286 4.8768)
			(end 2.286 2.032)
			(stroke
				(width 0.1524)
				(type default)
			)
			(layer "B.SilkS")
		)
		(fp_rect
			(start 2.1463 3.6449)
			(end -2.1463 -3.6449)
			(stroke
				(width 0)
				(type default)
			)
			(fill no)
			(layer "B.CrtYd")
		)
		(fp_poly
			(pts
				(xy 2.54 4.953) (xy 2.54 4.2926) (xy 3.81 4.2926) (xy 3.81 -4.2926) (xy 2.54 -4.2926) (xy 2.54 -4.953)
				(xy -2.54 -4.953) (xy -2.54 -4.2926) (xy -3.81 -4.2926) (xy -3.81 -1.6256) (xy -2.1463 -1.6256)
				(xy -2.1463 -3.6449) (xy 2.1463 -3.6449) (xy 2.1463 3.6449) (xy -2.1463 3.6449) (xy -2.1463 -1.6129)
				(xy -3.81 -1.6129) (xy -3.81 4.2926) (xy -2.54 4.2926) (xy -2.54 4.953)
			)
			(stroke
				(width 0)
				(type default)
			)
			(fill no)
			(layer "B.CrtYd")
		)
		(fp_rect
			(start -2.54 4.2926)
			(end -3.81 -4.2926)
			(stroke
				(width 0)
				(type default)
			)
			(fill no)
			(layer "B.Fab")
		)
		(fp_rect
			(start 2.54 4.953)
			(end -2.54 -4.953)
			(stroke
				(width 0)
				(type default)
			)
			(fill no)
			(layer "B.Fab")
		)
		(fp_rect
			(start 3.81 4.2926)
			(end 2.54 -4.2926)
			(stroke
				(width 0)
				(type default)
			)
			(fill no)
			(layer "B.Fab")
		)
		(pad "1" smd rect
			(at 0 -3.1496 180)
			(size 2.413 2.286)
			(layers "B.Cu" "B.Mask" "B.Paste")
			(net "P5V_B_3")
		)
		(pad "2" smd rect
			(at 0 3.1496 180)
			(size 2.413 2.286)
			(layers "B.Cu" "B.Mask" "B.Paste")
			(net "GND")
		)
		(zone
			(layer "B.Cu")
			(hatch none 0.5)
			(connect_pads
				(clearance 0)
			)
			(min_thickness 0.25)
			(keepout
				(tracks allowed)
				(vias not_allowed)
				(pads allowed)
				(copperpour not_allowed)
				(footprints allowed)
			)
			(placement
				(enabled no)
				(sheetname "")
			)
			(fill
				(thermal_gap 0.5)
				(thermal_bridge_width 0.5)
				(island_removal_mode 0)
			)
			(polygon
				(pts
					(xy 475.1451 -221.80169) (xy 475.1451 -224.70999) (xy 478.1677 -224.70999) (xy 478.1677 -221.81439)
					(xy 478.1677 -221.48419) (xy 475.1451 -221.48419)
				)
			)
		)
		(zone
			(layer "B.Cu")
			(hatch none 0.5)
			(connect_pads
				(clearance 0)
			)
			(min_thickness 0.25)
			(keepout
				(tracks allowed)
				(vias not_allowed)
				(pads allowed)
				(copperpour not_allowed)
				(footprints allowed)
			)
			(placement
				(enabled no)
				(sheetname "")
			)
			(fill
				(thermal_gap 0.5)
				(thermal_bridge_width 0.5)
				(island_removal_mode 0)
			)
			(polygon
				(pts
					(xy 478.1677 -215.51519) (xy 475.1451 -215.51519) (xy 475.1451 -218.41079) (xy 475.1451 -218.74099)
					(xy 478.1677 -218.74099) (xy 478.1677 -218.41079)
				)
			)
		)
	)
	(footprint ""
		(layer "B.Cu")
		(at 167.7162 -371.856 90)
		(property "Reference" "R999"
			(at 0 0 90)
			(layer "B.SilkS")
			(hide yes)
			(effects
				(font
					(size 1.27 1.27)
				)
				(justify mirror)
			)
		)
		(property "Value" "10R2F-L-GP"
			(at -0.064008 -3.993896 90)
			(unlocked yes)
			(layer "B.Fab")
			(hide yes)
			(effects
				(font
					(size 1.016 1.016)
					(thickness 0.1524)
				)
				(justify mirror)
			)
		)
		(property "Device Type" "R402H14"
			(at -0.064008 -5.517896 90)
			(unlocked yes)
			(layer "B.Fab")
			(hide yes)
			(effects
				(font
					(size 1.016 1.016)
					(thickness 0.1524)
				)
				(justify mirror)
			)
		)
		(duplicate_pad_numbers_are_jumpers no)
		(fp_line
			(start 0.508 -0.9398)
			(end 0.508 0.9398)
			(stroke
				(width 0.1524)
				(type default)
			)
			(layer "B.SilkS")
		)
		(fp_line
			(start -0.508 -0.9398)
			(end 0.508 -0.9398)
			(stroke
				(width 0.1524)
				(type default)
			)
			(layer "B.SilkS")
		)
		(fp_rect
			(start 0.508 0.9398)
			(end -0.508 -0.9398)
			(stroke
				(width 0)
				(type default)
			)
			(fill no)
			(layer "B.CrtYd")
		)
		(fp_rect
			(start 0.508 0.9398)
			(end -0.508 -0.9398)
			(stroke
				(width 0)
				(type default)
			)
			(fill no)
			(layer "B.Fab")
		)
		(pad "1" smd custom
			(at 0 -0.4445 270)
			(size 0.1397 0.1397)
			(layers "B.Cu" "B.Mask" "B.Paste")
			(net "MB0_CM_SENSE_R1_N")
			(options
				(clearance outline)
				(anchor circle)
			)
			(primitives
				(gr_poly
					(pts
						(arc
							(start -0.1778 0.2794)
							(mid -0.249642 0.249642)
							(end -0.2794 0.1778)
						)
						(arc
							(start -0.2794 -0.1778)
							(mid -0.249642 -0.249642)
							(end -0.1778 -0.2794)
						)
						(arc
							(start 0.1778 -0.2794)
							(mid 0.249642 -0.249642)
							(end 0.2794 -0.1778)
						)
						(arc
							(start 0.2794 0.1778)
							(mid 0.249642 0.249642)
							(end 0.1778 0.2794)
						)
					)
					(width 0)
					(fill yes)
				)
			)
		)
		(pad "2" smd custom
			(at 0 0.4445 270)
			(size 0.1397 0.1397)
			(layers "B.Cu" "B.Mask" "B.Paste")
			(net "MB0_CM_SENSE_N")
			(options
				(clearance outline)
				(anchor circle)
			)
			(primitives
				(gr_poly
					(pts
						(arc
							(start -0.1778 0.2794)
							(mid -0.249642 0.249642)
							(end -0.2794 0.1778)
						)
						(arc
							(start -0.2794 -0.1778)
							(mid -0.249642 -0.249642)
							(end -0.1778 -0.2794)
						)
						(arc
							(start 0.1778 -0.2794)
							(mid 0.249642 -0.249642)
							(end 0.2794 -0.1778)
						)
						(arc
							(start 0.2794 0.1778)
							(mid 0.249642 0.249642)
							(end 0.1778 0.2794)
						)
					)
					(width 0)
					(fill yes)
				)
			)
		)
	)
	(footprint ""
		(layer "B.Cu")
		(at 56.801258 -110.912656 90)
		(property "Reference" "L4"
			(at 0 0 90)
			(layer "B.SilkS")
			(hide yes)
			(effects
				(font
					(size 1.27 1.27)
				)
				(justify mirror)
			)
		)
		(property "Value" "IND-1UH-191-GP"
			(at 6.7818 -2.1082 90)
			(unlocked yes)
			(layer "B.Fab")
			(hide yes)
			(effects
				(font
					(size 1.016 1.016)
					(thickness 0.1524)
				)
				(justify mirror)
			)
		)
		(property "Device Type" "L109100-2430-UH119"
			(at 6.7818 -3.6322 90)
			(unlocked yes)
			(layer "B.Fab")
			(hide yes)
			(effects
				(font
					(size 1.016 1.016)
					(thickness 0.1524)
				)
				(justify mirror)
			)
		)
		(duplicate_pad_numbers_are_jumpers no)
		(fp_line
			(start 5.2578 -6.4262)
			(end -5.2578 -6.4262)
			(stroke
				(width 0.1524)
				(type default)
			)
			(layer "B.SilkS")
		)
		(fp_line
			(start -5.2578 -6.4262)
			(end -5.2578 6.4262)
			(stroke
				(width 0.1524)
				(type default)
			)
			(layer "B.SilkS")
		)
		(fp_line
			(start 5.2578 6.4262)
			(end 5.2578 -6.4262)
			(stroke
				(width 0.1524)
				(type default)
			)
			(layer "B.SilkS")
		)
		(fp_line
			(start -5.2578 6.4262)
			(end 5.2578 6.4262)
			(stroke
				(width 0.1524)
				(type default)
			)
			(layer "B.SilkS")
		)
		(fp_rect
			(start 5.0038 5.4229)
			(end -5.0038 -5.4229)
			(stroke
				(width 0)
				(type default)
			)
			(fill no)
			(layer "B.CrtYd")
		)
		(fp_poly
			(pts
				(xy 5.5118 6.5024) (xy 5.5118 -6.5024) (xy -5.5118 -6.5024) (xy -5.5118 -0.8509) (xy -5.0038 -0.8509)
				(xy -5.0038 -5.4229) (xy 5.0038 -5.4229) (xy 5.0038 5.4229) (xy -5.0038 5.4229) (xy -5.0038 -0.8382)
				(xy -5.5118 -0.8382) (xy -5.5118 6.5024)
			)
			(stroke
				(width 0)
				(type default)
			)
			(fill no)
			(layer "B.CrtYd")
		)
		(fp_rect
			(start 5.5118 6.5024)
			(end -5.5118 -6.5024)
			(stroke
				(width 0)
				(type default)
			)
			(fill no)
			(layer "B.Fab")
		)
		(pad "1" smd rect
			(at 0 -4.396994 270)
			(size 3.5052 3.556)
			(layers "B.Cu" "B.Mask" "B.Paste")
			(net "P5V_B_2_LL")
		)
		(pad "2" smd rect
			(at 0 4.396994 270)
			(size 3.5052 3.556)
			(layers "B.Cu" "B.Mask" "B.Paste")
			(net "P5V_B_2")
		)
	)
	(footprint ""
		(layer "B.Cu")
		(at 206.756 -329.184 90)
		(property "Reference" "R1015"
			(at 0 0 90)
			(layer "B.SilkS")
			(hide yes)
			(effects
				(font
					(size 1.27 1.27)
				)
				(justify mirror)
			)
		)
		(property "Value" "10R5F-1-GP"
			(at 0 -8.9535 90)
			(unlocked yes)
			(layer "B.Fab")
			(hide yes)
			(effects
				(font
					(size 1.27 1.016)
					(thickness 0.1524)
				)
				(justify mirror)
			)
		)
		(property "Device Type" "R805H24"
			(at 0 -10.6299 90)
			(unlocked yes)
			(layer "B.Fab")
			(hide yes)
			(effects
				(font
					(size 1.27 1.016)
					(thickness 0.1524)
				)
				(justify mirror)
			)
		)
		(duplicate_pad_numbers_are_jumpers no)
		(fp_line
			(start 0.889 -1.7018)
			(end 0.889 0.2794)
			(stroke
				(width 0.1524)
				(type default)
			)
			(layer "B.SilkS")
		)
		(fp_line
			(start -0.889 -1.7018)
			(end 0.889 -1.7018)
			(stroke
				(width 0.1524)
				(type default)
			)
			(layer "B.SilkS")
		)
		(fp_line
			(start -0.889 -1.7018)
			(end -0.889 -0.381)
			(stroke
				(width 0.1524)
				(type default)
			)
			(layer "B.SilkS")
		)
		(fp_line
			(start 0.889 0.0762)
			(end 0.889 1.7018)
			(stroke
				(width 0.1524)
				(type default)
			)
			(layer "B.SilkS")
		)
		(fp_line
			(start 0.889 1.7018)
			(end -0.889 1.7018)
			(stroke
				(width 0.1524)
				(type default)
			)
			(layer "B.SilkS")
		)
		(fp_line
			(start -0.889 1.7018)
			(end -0.889 -0.508)
			(stroke
				(width 0.1524)
				(type default)
			)
			(layer "B.SilkS")
		)
		(fp_poly
			(pts
				(xy -0.9652 -1.778) (xy -0.9652 1.778) (xy 0.9652 1.778) (xy 0.9652 -1.778)
			)
			(stroke
				(width 0)
				(type default)
			)
			(fill no)
			(layer "B.CrtYd")
		)
		(fp_rect
			(start 0.9652 1.778)
			(end -0.9652 -1.778)
			(stroke
				(width 0)
				(type default)
			)
			(fill no)
			(layer "B.Fab")
		)
		(pad "1" smd rect
			(at 0 -0.9652 270)
			(size 1.397 1.143)
			(layers "B.Cu" "B.Mask" "B.Paste")
			(net "MB0_12V_CTRL_GATE1")
		)
		(pad "2" smd rect
			(at 0 0.9652 270)
			(size 1.397 1.143)
			(layers "B.Cu" "B.Mask" "B.Paste")
			(net "MB0_CM_GATE_R")
		)
	)
	(footprint ""
		(layer "B.Cu")
		(at 201.955654 -344.193114 90)
		(property "Reference" "Q196"
			(at 0 0 90)
			(layer "B.SilkS")
			(hide yes)
			(effects
				(font
					(size 1.27 1.27)
				)
				(justify mirror)
			)
		)
		(property "Value" "IRFH8201TRPBF-GP"
			(at 4.2164 -4.3688 90)
			(unlocked yes)
			(layer "B.Fab")
			(hide yes)
			(effects
				(font
					(size 1.016 1.016)
					(thickness 0.1524)
				)
				(justify mirror)
			)
		)
		(property "Device Type" "PPAK-5PH42"
			(at 4.2164 -5.8928 90)
			(unlocked yes)
			(layer "B.Fab")
			(hide yes)
			(effects
				(font
					(size 1.016 1.016)
					(thickness 0.1524)
				)
				(justify mirror)
			)
		)
		(duplicate_pad_numbers_are_jumpers no)
		(fp_line
			(start 2.8956 -2.794)
			(end -2.8956 -2.794)
			(stroke
				(width 0.1524)
				(type default)
			)
			(layer "B.SilkS")
		)
		(fp_line
			(start -2.8956 -2.794)
			(end -2.8956 4.826)
			(stroke
				(width 0.1524)
				(type default)
			)
			(layer "B.SilkS")
		)
		(fp_line
			(start 2.8956 4.826)
			(end 2.8956 -2.794)
			(stroke
				(width 0.1524)
				(type default)
			)
			(layer "B.SilkS")
		)
		(fp_line
			(start -2.8956 4.826)
			(end 2.8956 4.826)
			(stroke
				(width 0.1524)
				(type default)
			)
			(layer "B.SilkS")
		)
		(fp_line
			(start 3.0353 4.9276)
			(end 3.0353 3.9624)
			(stroke
				(width 0.3302)
				(type default)
			)
			(layer "B.SilkS")
		)
		(fp_line
			(start 1.9431 4.9276)
			(end 3.0353 4.9276)
			(stroke
				(width 0.3302)
				(type default)
			)
			(layer "B.SilkS")
		)
		(fp_poly
			(pts
				(xy 2.3622 5.334) (xy 1.4986 5.334) (xy 1.9304 4.9022)
			)
			(stroke
				(width 0)
				(type default)
			)
			(fill yes)
			(layer "B.SilkS")
		)
		(fp_poly
			(pts
				(xy 2.6416 -0.3556) (xy 0.3556 -0.3556) (xy 0.3556 -2.54) (xy 2.6416 -2.54)
			)
			(stroke
				(width 0)
				(type default)
			)
			(fill yes)
			(layer "B.Paste")
		)
		(fp_poly
			(pts
				(xy -0.3556 -0.3556) (xy -2.6416 -0.3556) (xy -2.6416 -2.54) (xy -0.3556 -2.54)
			)
			(stroke
				(width 0)
				(type default)
			)
			(fill yes)
			(layer "B.Paste")
		)
		(fp_poly
			(pts
				(xy 2.6416 2.54) (xy 0.3556 2.54) (xy 0.3556 0.3556) (xy 2.6416 0.3556)
			)
			(stroke
				(width 0)
				(type default)
			)
			(fill yes)
			(layer "B.Paste")
		)
		(fp_poly
			(pts
				(xy -0.3556 2.54) (xy -2.6416 2.54) (xy -2.6416 0.3556) (xy -0.3556 0.3556)
			)
			(stroke
				(width 0)
				(type default)
			)
			(fill yes)
			(layer "B.Paste")
		)
		(fp_rect
			(start 2.5781 3.9878)
			(end -2.5781 -2.1082)
			(stroke
				(width 0)
				(type default)
			)
			(fill no)
			(layer "B.CrtYd")
		)
		(fp_poly
			(pts
				(xy 3.1496 5.08) (xy 3.1496 -3.048) (xy -3.1496 -3.048) (xy -3.1496 3.9751) (xy -2.5781 3.9751)
				(xy -2.5781 -2.1082) (xy 2.5781 -2.1082) (xy 2.5781 3.9878) (xy -3.1496 3.9878) (xy -3.1496 5.08)
			)
			(stroke
				(width 0)
				(type default)
			)
			(fill no)
			(layer "B.CrtYd")
		)
		(fp_rect
			(start 3.1496 5.08)
			(end -3.1496 -3.048)
			(stroke
				(width 0)
				(type default)
			)
			(fill no)
			(layer "B.Fab")
		)
		(pad "1" smd rect
			(at 1.905 3.81 270)
			(size 0.762 1.524)
			(layers "B.Cu" "B.Mask" "B.Paste")
			(net "P12V_IN")
		)
		(pad "2" smd rect
			(at 0.635 3.81 270)
			(size 0.762 1.524)
			(layers "B.Cu" "B.Mask" "B.Paste")
			(net "P12V_IN")
		)
		(pad "3" smd rect
			(at -0.635 3.81 270)
			(size 0.762 1.524)
			(layers "B.Cu" "B.Mask" "B.Paste")
			(net "P12V_IN")
		)
		(pad "4" smd rect
			(at -1.905 3.81 270)
			(size 0.762 1.524)
			(layers "B.Cu" "B.Mask" "B.Paste")
			(net "MB0_12V_CTRL_GATE3")
		)
		(pad "5" smd rect
			(at 0 0 270)
			(size 5.2832 5.08)
			(layers "B.Cu" "B.Mask" "B.Paste")
			(net "MB0_P12V_IN_R")
		)
		(pad "6" smd rect
			(at -0.635 -2.032 270)
			(size 0.0254 0.0254)
			(layers "B.Cu" "B.Mask" "B.Paste")
			(net "MB0_P12V_IN_R")
		)
		(pad "7" smd rect
			(at 0.635 -2.032 270)
			(size 0.0254 0.0254)
			(layers "B.Cu" "B.Mask" "B.Paste")
			(net "MB0_P12V_IN_R")
		)
		(pad "8" smd rect
			(at 1.905 -2.032 270)
			(size 0.0254 0.0254)
			(layers "B.Cu" "B.Mask" "B.Paste")
			(net "MB0_P12V_IN_R")
		)
	)
	(footprint ""
		(layer "B.Cu")
		(at 460.0448 -229.6922 90)
		(property "Reference" "R1147"
			(at 0 0 90)
			(layer "B.SilkS")
			(hide yes)
			(effects
				(font
					(size 1.27 1.27)
				)
				(justify mirror)
			)
		)
		(property "Value" "71K5R2F-GP"
			(at -0.064008 -3.993896 90)
			(unlocked yes)
			(layer "B.Fab")
			(hide yes)
			(effects
				(font
					(size 1.016 1.016)
					(thickness 0.1524)
				)
				(justify mirror)
			)
		)
		(property "Device Type" "R402H16"
			(at -0.064008 -5.517896 90)
			(unlocked yes)
			(layer "B.Fab")
			(hide yes)
			(effects
				(font
					(size 1.016 1.016)
					(thickness 0.1524)
				)
				(justify mirror)
			)
		)
		(duplicate_pad_numbers_are_jumpers no)
		(fp_line
			(start 0.508 -0.9398)
			(end 0.508 0.9398)
			(stroke
				(width 0.1524)
				(type default)
			)
			(layer "B.SilkS")
		)
		(fp_line
			(start -0.508 -0.9398)
			(end 0.508 -0.9398)
			(stroke
				(width 0.1524)
				(type default)
			)
			(layer "B.SilkS")
		)
		(fp_rect
			(start 0.508 0.9398)
			(end -0.508 -0.9398)
			(stroke
				(width 0)
				(type default)
			)
			(fill no)
			(layer "B.CrtYd")
		)
		(fp_rect
			(start 0.508 0.9398)
			(end -0.508 -0.9398)
			(stroke
				(width 0)
				(type default)
			)
			(fill no)
			(layer "B.Fab")
		)
		(pad "1" smd custom
			(at 0 -0.4445 270)
			(size 0.1397 0.1397)
			(layers "B.Cu" "B.Mask" "B.Paste")
			(net "P5V_B_3_VFB")
			(options
				(clearance outline)
				(anchor circle)
			)
			(primitives
				(gr_poly
					(pts
						(arc
							(start -0.1778 0.2794)
							(mid -0.249642 0.249642)
							(end -0.2794 0.1778)
						)
						(arc
							(start -0.2794 -0.1778)
							(mid -0.249642 -0.249642)
							(end -0.1778 -0.2794)
						)
						(arc
							(start 0.1778 -0.2794)
							(mid 0.249642 -0.249642)
							(end 0.2794 -0.1778)
						)
						(arc
							(start 0.2794 0.1778)
							(mid 0.249642 0.249642)
							(end 0.1778 0.2794)
						)
					)
					(width 0)
					(fill yes)
				)
			)
		)
		(pad "2" smd custom
			(at 0 0.4445 270)
			(size 0.1397 0.1397)
			(layers "B.Cu" "B.Mask" "B.Paste")
			(net "P5V_B_3_VFB_R")
			(options
				(clearance outline)
				(anchor circle)
			)
			(primitives
				(gr_poly
					(pts
						(arc
							(start -0.1778 0.2794)
							(mid -0.249642 0.249642)
							(end -0.2794 0.1778)
						)
						(arc
							(start -0.2794 -0.1778)
							(mid -0.249642 -0.249642)
							(end -0.1778 -0.2794)
						)
						(arc
							(start 0.1778 -0.2794)
							(mid 0.249642 -0.249642)
							(end 0.2794 -0.1778)
						)
						(arc
							(start 0.2794 0.1778)
							(mid 0.249642 0.249642)
							(end 0.1778 0.2794)
						)
					)
					(width 0)
					(fill yes)
				)
			)
		)
	)
)
